(kicad_pcb
	(version 20260206)
	(generator "pcbnew")
	(generator_version "10.0")
	(general
		(thickness 1.6)
		(legacy_teardrops no)
	)
	(paper "A4")
	(title_block
		(title "Bryce Canyon_SCC_16316-1_OCP.brd")
		(comment 1 "Bryce Canyon / footprints 1298-1306 of 1561")
	)
	(layers
		(0 "F.Cu" signal "TOP")
		(4 "In1.Cu" signal "L2GND")
		(6 "In2.Cu" signal "L3")
		(8 "In3.Cu" signal "L4VCC")
		(10 "In4.Cu" signal "L5VCC")
		(12 "In5.Cu" signal "L6")
		(14 "In6.Cu" signal "L7GND")
		(2 "B.Cu" signal "BOTTOM")
		(9 "F.Adhes" user "F.Adhesive")
		(11 "B.Adhes" user "B.Adhesive")
		(13 "F.Paste" user "Package Geometry/Pastemask Top")
		(15 "B.Paste" user "Package Geometry/Pastemask Bottom")
		(5 "F.SilkS" user "Ref Des/Silkscreen Top")
		(7 "B.SilkS" user "Ref Des/Silkscreen Bottom")
		(1 "F.Mask" user "Board Geometry/Soldermask Top")
		(3 "B.Mask" user "Board Geometry/Soldermask Bottom")
		(17 "Dwgs.User" user "User.Drawings")
		(19 "Cmts.User" user "User.Comments")
		(21 "Eco1.User" user "User.Eco1")
		(23 "Eco2.User" user "User.Eco2")
		(25 "Edge.Cuts" user "Board Geometry/Outline")
		(27 "Margin" user)
		(31 "F.CrtYd" user "Package Geometry/Place Bound Top")
		(29 "B.CrtYd" user "Package Geometry/Place Bound Bottom")
		(35 "F.Fab" user "Ref Des/Assembly Top")
		(33 "B.Fab" user "Ref Des/Assembly Bottom")
	)
	(footprint ""
		(layer "B.Cu")
		(at 117.983 -44.2214 180)
		(property "Reference" "C60"
			(at 0 0 0)
			(layer "B.SilkS")
			(hide yes)
			(effects
				(font
					(size 1.27 1.27)
				)
				(justify mirror)
			)
		)
		(property "Value" "SCD01U16V1KX-GP"
			(at 2.8321 -1.7399 180)
			(unlocked yes)
			(layer "B.Fab")
			(hide yes)
			(effects
				(font
					(size 1.016 1.016)
					(thickness 0.1524)
				)
				(justify mirror)
			)
		)
		(property "Device Type" "C0201H13"
			(at 2.8321 -3.2639 180)
			(unlocked yes)
			(layer "B.Fab")
			(hide yes)
			(effects
				(font
					(size 1.016 1.016)
					(thickness 0.1524)
				)
				(justify mirror)
			)
		)
		(duplicate_pad_numbers_are_jumpers no)
		(fp_rect
			(start 0.2794 0.6477)
			(end -0.2794 -0.6477)
			(stroke
				(width 0)
				(type default)
			)
			(fill no)
			(layer "B.CrtYd")
		)
		(fp_rect
			(start 0.2794 0.6477)
			(end -0.2794 -0.6477)
			(stroke
				(width 0)
				(type default)
			)
			(fill no)
			(layer "B.Fab")
		)
		(pad "1" smd custom
			(at 0 -0.2794)
			(size 0.0762 0.0762)
			(layers "B.Cu" "B.Mask" "B.Paste")
			(net "PHY_DPB_TO_SCC_34_DN")
			(options
				(clearance outline)
				(anchor circle)
			)
			(primitives
				(gr_poly
					(pts
						(arc
							(start 0.1524 0.127)
							(mid 0.137521 0.162921)
							(end 0.1016 0.1778)
						)
						(arc
							(start -0.1016 0.1778)
							(mid -0.137521 0.162921)
							(end -0.1524 0.127)
						)
						(arc
							(start -0.1524 -0.127)
							(mid -0.137521 -0.162921)
							(end -0.1016 -0.1778)
						)
						(arc
							(start 0.1016 -0.1778)
							(mid 0.137521 -0.162921)
							(end 0.1524 -0.127)
						)
					)
					(width 0)
					(fill yes)
				)
			)
		)
		(pad "2" smd custom
			(at 0 0.2794)
			(size 0.0762 0.0762)
			(layers "B.Cu" "B.Mask" "B.Paste")
			(net "PHY_DPB_TO_SCC_C_34_DN")
			(options
				(clearance outline)
				(anchor circle)
			)
			(primitives
				(gr_poly
					(pts
						(arc
							(start 0.1524 0.127)
							(mid 0.137521 0.162921)
							(end 0.1016 0.1778)
						)
						(arc
							(start -0.1016 0.1778)
							(mid -0.137521 0.162921)
							(end -0.1524 0.127)
						)
						(arc
							(start -0.1524 -0.127)
							(mid -0.137521 -0.162921)
							(end -0.1016 -0.1778)
						)
						(arc
							(start 0.1016 -0.1778)
							(mid 0.137521 -0.162921)
							(end 0.1524 -0.127)
						)
					)
					(width 0)
					(fill yes)
				)
			)
		)
	)
	(footprint ""
		(layer "B.Cu")
		(at 130.2258 -80.899 180)
		(property "Reference" "C146"
			(at 0 0 0)
			(layer "B.SilkS")
			(hide yes)
			(effects
				(font
					(size 1.27 1.27)
				)
				(justify mirror)
			)
		)
		(property "Value" "SCD1U6D3V1KX-GP"
			(at 2.8321 -1.7399 180)
			(unlocked yes)
			(layer "B.Fab")
			(hide yes)
			(effects
				(font
					(size 1.016 1.016)
					(thickness 0.1524)
				)
				(justify mirror)
			)
		)
		(property "Device Type" "C0201H13"
			(at 2.8321 -3.2639 180)
			(unlocked yes)
			(layer "B.Fab")
			(hide yes)
			(effects
				(font
					(size 1.016 1.016)
					(thickness 0.1524)
				)
				(justify mirror)
			)
		)
		(duplicate_pad_numbers_are_jumpers no)
		(fp_rect
			(start 0.2794 0.6477)
			(end -0.2794 -0.6477)
			(stroke
				(width 0)
				(type default)
			)
			(fill no)
			(layer "B.CrtYd")
		)
		(fp_rect
			(start 0.2794 0.6477)
			(end -0.2794 -0.6477)
			(stroke
				(width 0)
				(type default)
			)
			(fill no)
			(layer "B.Fab")
		)
		(pad "1" smd custom
			(at 0 -0.2794)
			(size 0.0762 0.0762)
			(layers "B.Cu" "B.Mask" "B.Paste")
			(net "P1V8_E")
			(options
				(clearance outline)
				(anchor circle)
			)
			(primitives
				(gr_poly
					(pts
						(arc
							(start 0.1524 0.127)
							(mid 0.137521 0.162921)
							(end 0.1016 0.1778)
						)
						(arc
							(start -0.1016 0.1778)
							(mid -0.137521 0.162921)
							(end -0.1524 0.127)
						)
						(arc
							(start -0.1524 -0.127)
							(mid -0.137521 -0.162921)
							(end -0.1016 -0.1778)
						)
						(arc
							(start 0.1016 -0.1778)
							(mid 0.137521 -0.162921)
							(end 0.1524 -0.127)
						)
					)
					(width 0)
					(fill yes)
				)
			)
		)
		(pad "2" smd custom
			(at 0 0.2794)
			(size 0.0762 0.0762)
			(layers "B.Cu" "B.Mask" "B.Paste")
			(net "GND")
			(options
				(clearance outline)
				(anchor circle)
			)
			(primitives
				(gr_poly
					(pts
						(arc
							(start 0.1524 0.127)
							(mid 0.137521 0.162921)
							(end 0.1016 0.1778)
						)
						(arc
							(start -0.1016 0.1778)
							(mid -0.137521 0.162921)
							(end -0.1524 0.127)
						)
						(arc
							(start -0.1524 -0.127)
							(mid -0.137521 -0.162921)
							(end -0.1016 -0.1778)
						)
						(arc
							(start 0.1016 -0.1778)
							(mid 0.137521 -0.162921)
							(end 0.1524 -0.127)
						)
					)
					(width 0)
					(fill yes)
				)
			)
		)
	)
	(footprint ""
		(layer "B.Cu")
		(at 178.420014 -20.579842 90)
		(property "Reference" "C323"
			(at 0 0 90)
			(layer "B.SilkS")
			(hide yes)
			(effects
				(font
					(size 1.27 1.27)
				)
				(justify mirror)
			)
		)
		(property "Value" "SCD22U10V1KX-GP"
			(at 2.8321 -1.7399 90)
			(unlocked yes)
			(layer "B.Fab")
			(hide yes)
			(effects
				(font
					(size 1.016 1.016)
					(thickness 0.1524)
				)
				(justify mirror)
			)
		)
		(property "Device Type" "C0201H13"
			(at 2.8321 -3.2639 90)
			(unlocked yes)
			(layer "B.Fab")
			(hide yes)
			(effects
				(font
					(size 1.016 1.016)
					(thickness 0.1524)
				)
				(justify mirror)
			)
		)
		(duplicate_pad_numbers_are_jumpers no)
		(fp_rect
			(start 0.2794 0.6477)
			(end -0.2794 -0.6477)
			(stroke
				(width 0)
				(type default)
			)
			(fill no)
			(layer "B.CrtYd")
		)
		(fp_rect
			(start 0.2794 0.6477)
			(end -0.2794 -0.6477)
			(stroke
				(width 0)
				(type default)
			)
			(fill no)
			(layer "B.Fab")
		)
		(pad "1" smd custom
			(at 0 -0.2794 270)
			(size 0.0762 0.0762)
			(layers "B.Cu" "B.Mask" "B.Paste")
			(net "PCIE_SCC_TO_COMP_C_6_DP")
			(options
				(clearance outline)
				(anchor circle)
			)
			(primitives
				(gr_poly
					(pts
						(arc
							(start 0.1524 0.127)
							(mid 0.137521 0.162921)
							(end 0.1016 0.1778)
						)
						(arc
							(start -0.1016 0.1778)
							(mid -0.137521 0.162921)
							(end -0.1524 0.127)
						)
						(arc
							(start -0.1524 -0.127)
							(mid -0.137521 -0.162921)
							(end -0.1016 -0.1778)
						)
						(arc
							(start 0.1016 -0.1778)
							(mid 0.137521 -0.162921)
							(end 0.1524 -0.127)
						)
					)
					(width 0)
					(fill yes)
				)
			)
		)
		(pad "2" smd custom
			(at 0 0.2794 270)
			(size 0.0762 0.0762)
			(layers "B.Cu" "B.Mask" "B.Paste")
			(net "PCIE_SCC_TO_COMP_6_DP")
			(options
				(clearance outline)
				(anchor circle)
			)
			(primitives
				(gr_poly
					(pts
						(arc
							(start 0.1524 0.127)
							(mid 0.137521 0.162921)
							(end 0.1016 0.1778)
						)
						(arc
							(start -0.1016 0.1778)
							(mid -0.137521 0.162921)
							(end -0.1524 0.127)
						)
						(arc
							(start -0.1524 -0.127)
							(mid -0.137521 -0.162921)
							(end -0.1016 -0.1778)
						)
						(arc
							(start 0.1016 -0.1778)
							(mid 0.137521 -0.162921)
							(end 0.1524 -0.127)
						)
					)
					(width 0)
					(fill yes)
				)
			)
		)
	)
	(footprint ""
		(layer "B.Cu")
		(at 62.1792 -56.7182 -90)
		(property "Reference" "C708"
			(at 0 0 90)
			(layer "B.SilkS")
			(hide yes)
			(effects
				(font
					(size 1.27 1.27)
				)
				(justify mirror)
			)
		)
		(property "Value" "SC10U6D3V5KX-4GP"
			(at 0.0762 -6.1214 270)
			(unlocked yes)
			(layer "B.Fab")
			(hide yes)
			(effects
				(font
					(size 1.016 1.016)
					(thickness 0.1524)
				)
				(justify mirror)
			)
		)
		(property "Device Type" "C805H58"
			(at 0.0762 -8.1534 270)
			(unlocked yes)
			(layer "B.Fab")
			(hide yes)
			(effects
				(font
					(size 1.016 1.016)
					(thickness 0.1524)
				)
				(justify mirror)
			)
		)
		(duplicate_pad_numbers_are_jumpers no)
		(fp_line
			(start -0.635 0)
			(end 0.635 0)
			(stroke
				(width 0.508)
				(type default)
			)
			(layer "B.SilkS")
		)
		(fp_rect
			(start 0.9652 1.778)
			(end -0.9652 -1.778)
			(stroke
				(width 0)
				(type default)
			)
			(fill no)
			(layer "B.CrtYd")
		)
		(fp_poly
			(pts
				(xy 0.9652 -1.778) (xy -0.9652 -1.778) (xy -0.9652 1.778) (xy 0.9652 1.778)
			)
			(stroke
				(width 0)
				(type default)
			)
			(fill no)
			(layer "B.Fab")
		)
		(pad "1" smd rect
			(at 0 -0.9652 90)
			(size 1.397 1.143)
			(layers "B.Cu" "B.Mask" "B.Paste")
			(net "P0V9")
		)
		(pad "2" smd rect
			(at 0 0.9652 90)
			(size 1.397 1.143)
			(layers "B.Cu" "B.Mask" "B.Paste")
			(net "GND")
		)
	)
	(footprint ""
		(layer "B.Cu")
		(at 198.882 -28.321 180)
		(property "Reference" "C378"
			(at 0 0 0)
			(layer "B.SilkS")
			(hide yes)
			(effects
				(font
					(size 1.27 1.27)
				)
				(justify mirror)
			)
		)
		(property "Value" "SC10U6D3V5KX-4GP"
			(at 0.0762 -6.1214 180)
			(unlocked yes)
			(layer "B.Fab")
			(hide yes)
			(effects
				(font
					(size 1.016 1.016)
					(thickness 0.1524)
				)
				(justify mirror)
			)
		)
		(property "Device Type" "C805H58"
			(at 0.0762 -8.1534 180)
			(unlocked yes)
			(layer "B.Fab")
			(hide yes)
			(effects
				(font
					(size 1.016 1.016)
					(thickness 0.1524)
				)
				(justify mirror)
			)
		)
		(duplicate_pad_numbers_are_jumpers no)
		(fp_line
			(start -0.635 0)
			(end 0.635 0)
			(stroke
				(width 0.508)
				(type default)
			)
			(layer "B.SilkS")
		)
		(fp_rect
			(start 0.9652 1.778)
			(end -0.9652 -1.778)
			(stroke
				(width 0)
				(type default)
			)
			(fill no)
			(layer "B.CrtYd")
		)
		(fp_poly
			(pts
				(xy 0.9652 -1.778) (xy -0.9652 -1.778) (xy -0.9652 1.778) (xy 0.9652 1.778)
			)
			(stroke
				(width 0)
				(type default)
			)
			(fill no)
			(layer "B.Fab")
		)
		(pad "1" smd rect
			(at 0 -0.9652)
			(size 1.397 1.143)
			(layers "B.Cu" "B.Mask" "B.Paste")
			(net "PCE_VDDH")
		)
		(pad "2" smd rect
			(at 0 0.9652)
			(size 1.397 1.143)
			(layers "B.Cu" "B.Mask" "B.Paste")
			(net "GND")
		)
	)
	(footprint ""
		(layer "B.Cu")
		(at 189.4078 -27.6098 90)
		(property "Reference" "TP62"
			(at 0 0 90)
			(layer "B.SilkS")
			(hide yes)
			(effects
				(font
					(size 1.27 1.27)
				)
				(justify mirror)
			)
		)
		(property "Value" "TPAD28-2-GP"
			(at 0.0127 -1.6637 90)
			(unlocked yes)
			(layer "B.Fab")
			(hide yes)
			(effects
				(font
					(size 1.016 1.016)
					(thickness 0.1524)
				)
				(justify mirror)
			)
		)
		(property "Device Type" "TPAD28"
			(at 0.0127 -3.1877 90)
			(unlocked yes)
			(layer "B.Fab")
			(hide yes)
			(effects
				(font
					(size 1.016 1.016)
					(thickness 0.1524)
				)
				(justify mirror)
			)
		)
		(duplicate_pad_numbers_are_jumpers no)
		(fp_poly
			(pts
				(arc
					(start 0 0.3556)
					(mid 0 -0.3556)
					(end 0 0.3556)
				)
			)
			(stroke
				(width 0)
				(type default)
			)
			(fill no)
			(layer "B.CrtYd")
		)
		(fp_poly
			(pts
				(arc
					(start 0 0.6096)
					(mid 0 -0.6096)
					(end 0 0.6096)
				)
			)
			(stroke
				(width 0)
				(type default)
			)
			(fill no)
			(layer "B.Fab")
		)
		(pad "1" smd circle
			(at 0 0 270)
			(size 0.7112 0.7112)
			(layers "B.Cu" "B.Mask" "B.Paste")
			(net "IOC_GPIO_9")
		)
	)
	(footprint ""
		(layer "B.Cu")
		(at 107.4928 -57.4802)
		(property "Reference" "C253"
			(at 0 0 0)
			(layer "B.SilkS")
			(hide yes)
			(effects
				(font
					(size 1.27 1.27)
				)
				(justify mirror)
			)
		)
		(property "Value" "SCD1U6D3V1KX-GP"
			(at 2.8321 -1.7399 0)
			(unlocked yes)
			(layer "B.Fab")
			(hide yes)
			(effects
				(font
					(size 1.016 1.016)
					(thickness 0.1524)
				)
				(justify mirror)
			)
		)
		(property "Device Type" "C0201H13"
			(at 2.8321 -3.2639 0)
			(unlocked yes)
			(layer "B.Fab")
			(hide yes)
			(effects
				(font
					(size 1.016 1.016)
					(thickness 0.1524)
				)
				(justify mirror)
			)
		)
		(duplicate_pad_numbers_are_jumpers no)
		(fp_rect
			(start 0.2794 0.6477)
			(end -0.2794 -0.6477)
			(stroke
				(width 0)
				(type default)
			)
			(fill no)
			(layer "B.CrtYd")
		)
		(fp_rect
			(start 0.2794 0.6477)
			(end -0.2794 -0.6477)
			(stroke
				(width 0)
				(type default)
			)
			(fill no)
			(layer "B.Fab")
		)
		(pad "1" smd custom
			(at 0 -0.2794 180)
			(size 0.0762 0.0762)
			(layers "B.Cu" "B.Mask" "B.Paste")
			(net "GB_VDDA")
			(options
				(clearance outline)
				(anchor circle)
			)
			(primitives
				(gr_poly
					(pts
						(arc
							(start 0.1524 0.127)
							(mid 0.137521 0.162921)
							(end 0.1016 0.1778)
						)
						(arc
							(start -0.1016 0.1778)
							(mid -0.137521 0.162921)
							(end -0.1524 0.127)
						)
						(arc
							(start -0.1524 -0.127)
							(mid -0.137521 -0.162921)
							(end -0.1016 -0.1778)
						)
						(arc
							(start 0.1016 -0.1778)
							(mid 0.137521 -0.162921)
							(end 0.1524 -0.127)
						)
					)
					(width 0)
					(fill yes)
				)
			)
		)
		(pad "2" smd custom
			(at 0 0.2794 180)
			(size 0.0762 0.0762)
			(layers "B.Cu" "B.Mask" "B.Paste")
			(net "GND")
			(options
				(clearance outline)
				(anchor circle)
			)
			(primitives
				(gr_poly
					(pts
						(arc
							(start 0.1524 0.127)
							(mid 0.137521 0.162921)
							(end 0.1016 0.1778)
						)
						(arc
							(start -0.1016 0.1778)
							(mid -0.137521 0.162921)
							(end -0.1524 0.127)
						)
						(arc
							(start -0.1524 -0.127)
							(mid -0.137521 -0.162921)
							(end -0.1016 -0.1778)
						)
						(arc
							(start 0.1016 -0.1778)
							(mid 0.137521 -0.162921)
							(end 0.1524 -0.127)
						)
					)
					(width 0)
					(fill yes)
				)
			)
		)
	)
	(footprint ""
		(layer "B.Cu")
		(at 139.4968 -89.6874)
		(property "Reference" "R52"
			(at 0 0 0)
			(layer "B.SilkS")
			(hide yes)
			(effects
				(font
					(size 1.27 1.27)
				)
				(justify mirror)
			)
		)
		(property "Value" "4K7R2F-GP"
			(at -0.064008 -3.993896 0)
			(unlocked yes)
			(layer "B.Fab")
			(hide yes)
			(effects
				(font
					(size 1.016 1.016)
					(thickness 0.1524)
				)
				(justify mirror)
			)
		)
		(property "Device Type" "R402H16"
			(at -0.064008 -5.517896 0)
			(unlocked yes)
			(layer "B.Fab")
			(hide yes)
			(effects
				(font
					(size 1.016 1.016)
					(thickness 0.1524)
				)
				(justify mirror)
			)
		)
		(duplicate_pad_numbers_are_jumpers no)
		(fp_line
			(start -0.508 -0.9398)
			(end 0.508 -0.9398)
			(stroke
				(width 0.1524)
				(type default)
			)
			(layer "B.SilkS")
		)
		(fp_line
			(start 0.508 -0.9398)
			(end 0.508 0.9398)
			(stroke
				(width 0.1524)
				(type default)
			)
			(layer "B.SilkS")
		)
		(fp_rect
			(start 0.508 0.9398)
			(end -0.508 -0.9398)
			(stroke
				(width 0)
				(type default)
			)
			(fill no)
			(layer "B.CrtYd")
		)
		(fp_rect
			(start 0.508 0.9398)
			(end -0.508 -0.9398)
			(stroke
				(width 0)
				(type default)
			)
			(fill no)
			(layer "B.Fab")
		)
		(pad "1" smd custom
			(at 0 -0.4445 180)
			(size 0.1397 0.1397)
			(layers "B.Cu" "B.Mask" "B.Paste")
			(net "P1V8_E")
			(options
				(clearance outline)
				(anchor circle)
			)
			(primitives
				(gr_poly
					(pts
						(arc
							(start -0.1778 0.2794)
							(mid -0.249642 0.249642)
							(end -0.2794 0.1778)
						)
						(arc
							(start -0.2794 -0.1778)
							(mid -0.249642 -0.249642)
							(end -0.1778 -0.2794)
						)
						(arc
							(start 0.1778 -0.2794)
							(mid 0.249642 -0.249642)
							(end 0.2794 -0.1778)
						)
						(arc
							(start 0.2794 0.1778)
							(mid 0.249642 0.249642)
							(end 0.1778 0.2794)
						)
					)
					(width 0)
					(fill yes)
				)
			)
		)
		(pad "2" smd custom
			(at 0 0.4445 180)
			(size 0.1397 0.1397)
			(layers "B.Cu" "B.Mask" "B.Paste")
			(net "I2C_SCC_SCL2_LS")
			(options
				(clearance outline)
				(anchor circle)
			)
			(primitives
				(gr_poly
					(pts
						(arc
							(start -0.1778 0.2794)
							(mid -0.249642 0.249642)
							(end -0.2794 0.1778)
						)
						(arc
							(start -0.2794 -0.1778)
							(mid -0.249642 -0.249642)
							(end -0.1778 -0.2794)
						)
						(arc
							(start 0.1778 -0.2794)
							(mid 0.249642 -0.249642)
							(end 0.2794 -0.1778)
						)
						(arc
							(start 0.2794 0.1778)
							(mid 0.249642 0.249642)
							(end 0.1778 0.2794)
						)
					)
					(width 0)
					(fill yes)
				)
			)
		)
	)
	(footprint ""
		(layer "B.Cu")
		(at 120.7516 -59.4487)
		(property "Reference" "C276"
			(at 0 0 0)
			(layer "B.SilkS")
			(hide yes)
			(effects
				(font
					(size 1.27 1.27)
				)
				(justify mirror)
			)
		)
		(property "Value" "SCD1U6D3V1KX-GP"
			(at 2.8321 -1.7399 0)
			(unlocked yes)
			(layer "B.Fab")
			(hide yes)
			(effects
				(font
					(size 1.016 1.016)
					(thickness 0.1524)
				)
				(justify mirror)
			)
		)
		(property "Device Type" "C0201H13"
			(at 2.8321 -3.2639 0)
			(unlocked yes)
			(layer "B.Fab")
			(hide yes)
			(effects
				(font
					(size 1.016 1.016)
					(thickness 0.1524)
				)
				(justify mirror)
			)
		)
		(duplicate_pad_numbers_are_jumpers no)
		(fp_rect
			(start 0.2794 0.6477)
			(end -0.2794 -0.6477)
			(stroke
				(width 0)
				(type default)
			)
			(fill no)
			(layer "B.CrtYd")
		)
		(fp_rect
			(start 0.2794 0.6477)
			(end -0.2794 -0.6477)
			(stroke
				(width 0)
				(type default)
			)
			(fill no)
			(layer "B.Fab")
		)
		(pad "1" smd custom
			(at 0 -0.2794 180)
			(size 0.0762 0.0762)
			(layers "B.Cu" "B.Mask" "B.Paste")
			(net "GB_VDDA")
			(options
				(clearance outline)
				(anchor circle)
			)
			(primitives
				(gr_poly
					(pts
						(arc
							(start 0.1524 0.127)
							(mid 0.137521 0.162921)
							(end 0.1016 0.1778)
						)
						(arc
							(start -0.1016 0.1778)
							(mid -0.137521 0.162921)
							(end -0.1524 0.127)
						)
						(arc
							(start -0.1524 -0.127)
							(mid -0.137521 -0.162921)
							(end -0.1016 -0.1778)
						)
						(arc
							(start 0.1016 -0.1778)
							(mid 0.137521 -0.162921)
							(end 0.1524 -0.127)
						)
					)
					(width 0)
					(fill yes)
				)
			)
		)
		(pad "2" smd custom
			(at 0 0.2794 180)
			(size 0.0762 0.0762)
			(layers "B.Cu" "B.Mask" "B.Paste")
			(net "GND")
			(options
				(clearance outline)
				(anchor circle)
			)
			(primitives
				(gr_poly
					(pts
						(arc
							(start 0.1524 0.127)
							(mid 0.137521 0.162921)
							(end 0.1016 0.1778)
						)
						(arc
							(start -0.1016 0.1778)
							(mid -0.137521 0.162921)
							(end -0.1524 0.127)
						)
						(arc
							(start -0.1524 -0.127)
							(mid -0.137521 -0.162921)
							(end -0.1016 -0.1778)
						)
						(arc
							(start 0.1016 -0.1778)
							(mid 0.137521 -0.162921)
							(end 0.1524 -0.127)
						)
					)
					(width 0)
					(fill yes)
				)
			)
		)
	)
)
